# OCXO_DaughterCard_AbraconAOCJYR.xlsx — OCXO_DaughterCard_AbraconAOCJYR (bom)
| Comment | Description | Designator | Footprint | LibRef | Quantity |
| 0_1%_0402 |  | R11, R12, R17, R18, R19, R24, R25, R26, R30, R32 | RESC1005X40X25NL05T10 | CMP-1011-00001-2 | 10 |
| 0_5%_0603 | Chip Resistor, 0 Ohm, +/- 5%, 0.1 W, -55 to 155 degC, 0603 (1608 Metric), RoHS, Tape and Reel | R16, R23 | RESC1608X55X25ML10T15 | CMP-2100-03667-1 | 2 |
| 4.7K_1%_0402 | Chip Resistor, 4.7 KOhm, +/- 1%, 0.1 W, -55 to 155 degC, 0402 (1005 Metric), RoHS, Tape and Reel | R27, R28, R35, R36 | RESC1005X40X25LL05T05 | CMP-2002-01154-4 | 4 |
| 4871 | Round Standoff Threaded #2-56 Steel 0.063" (1.60mm) 1/16" | P13, P14, P15, P16 | Keystone_4871 | Keystone_4871 | 4 |
| Abracon_AOCJYR-10.000MHZ-M5625LF | OSC, OCXO, 10.000MHZ, 25PPB STAB, LVCMOS, 3.3V, 9.7X7.5X4.3MM, SMT | Y3 | OSC004_600_970x750x410_AOCJYR | COR-CMP-00013-2 | 1 |
| Kemet_T491B476K010AT | CAP TANT 47UF 10% 10V 1411 | C5, C15, C16 | CAPMP3528X210N_T520 | CAP-CMP-00042-1 | 3 |
| LMS1587IS-3.3/NOPB | 3A Low Dropout Fast Response Regulators, 3-pin TO-263, Pb-Free | U1 | KTT0003B_L | CMP-0062-00189-5 | 1 |
| Microchip_AT24MAC602-XHM-B | IC, EEPROM, AT24MAC602, 2K-BIT (256 X 8), 1MHZ, I2C, 1.7V - 5.5V, TSSOP-8 | U2 | TSSOP65P640X120-8N | MEM-CMP-00010-1 | 1 |
| Mill-Max_8600-0-05-80-00-00-03-0 | CONN, PC PIN, PRESS-FIT, 10.16MM LENGTH, TIN, TH | P1, P2, P3, P4, P5, P6, P7, P8, P11, P12 | TH001V_109DIA_000mt_8600-0 | CON-CMP-00162-1 | 10 |
| Molex_539160208 | CONN, B2B/FPC, HEADER, 20-POS, 0.5MM PITCH, 4.0MM H, VERT, GOLD, SMT | P10 | SM020V_50_730x310x337_000mt_53916 | CON-CMP-00163-2 | 1 |
| Murata_GRM21BR61A226ME51L | CAP, CER, X5R, 22UF, 20%, 10V, 0805, 1.40MM T | C2, C3, C4 | CAPC2013X140N | CAP-CMP-00519-3 | 3 |
| Murata_GRM188D71A106MA73D | CAP, CER, X7T, 10UF, 20%, 10V, 0603, 1.00MM T | C8, C10, C18, C20 | CAPC1608X100N | CAP-CMP-00449-3 | 4 |
| Murata_GRM188R61A106ME69D | CAP, CER, X5R, 10UF, 20%, 10V, 0603, 0.80MM T | C22 | CAPC1608X090N | CMP-CAP-00380-1 | 1 |
| NXP_PCT2075TP,147 | SENSOR DIGITAL -55C-125C 8HWSON | U5 | SON50P300X200X80-HS-9N_EP160x160_IPC | SNS-CMP-00004-1 | 1 |
| Panasonic_ERJ-2RKF1003X | RES, 100K OHM, 1%, 1/10W, 100PPM/C, 0402 | R4 | RESC1005X040N | RES-CMP-00289-3 | 1 |
| Samsung Electro-Mechanics_CL05B104JO5NNNC | CAP, CER, X7R, 0.1UF, 5%, 16V, 0402, 0.55MM T | C1, C6, C7, C9, C11, C13, C17, C19, C21, C23 | CAPC1005X055N | CAP-CMP-00271-3, CMP-CAP-00082-2 | 10 |
| Samtec_HTSW-102-07-T-S | CONN, PIN, HEADER, 2POS, 2.54MM PITCH, 8.38MM H, VERT, TIN, TH | P9 | TH002_254_508x254x838_000mt_HTSW | CON-CMP-00061-3 | 1 |
| Stackpole Electronics, Inc._HCJ0402ZT0R00 | RES, 0.0 OHM, 1/8W, 6.5A, 0402 | R6, R7, R8 | RESC1005X045N | RES-CMP-00382-3 | 3 |
| Stackpole Electronics, Inc._RMCF1210ZT0R00 | RES, 0.0 OHM, 3A, 1/2W, 1210 | R1 | RESC3225X070N | RES-CMP-00829-3 | 1 |
| TDK_MPZ1608S601ATA00 | FERRITE BEAD, 600 OHM @100MHZ, 25%, 1A, 0.150 OHM DCR, 0603, 0.95MM T | FL1, FL2 | INDC1608X095N | FER-CMP-00057-5 | 2 |
| TI_DS90LV027AQMA/NOPB | IC, DRIVER, DS90LV027AQ, DUAL, DIFF, LVDS, 600MBPS, SOIC-8 | U3 | SOP127P600X175_8N | INT-CMP-00018-2 | 1 |
| TI_DS90LV028AQMA/NOPB | IC, RVCR, DS90LV028AQ-Q1, DUAL, DIFF, LVDS, 400MBPS, SOIC-8 | U4 | SOP127P600X175_8N | INT-CMP-00017-4 | 1 |
| Wurth_9774040243R | STANDOFF, ROUND, M2X0.4 STEEL 4MM, 9774040243R | J1, J2 | TH000V_300DIAx400_001mt_9774040243R | CON-CMP-00164-1 | 2 |
| Yageo_CC0402KRX7R7BB103 | CAP, CER, X7R, 0.01UF, 10%, 16V, 0402, 0.55MM T | C12, C14 | CAPC1005X055N | CAP-CMP-00257-3 | 2 |
| Yageo_RC0201FR-0710KL | RES, 10K OHM, 1%, 1/20W, 200PPM/C, 0201 | R34 | RESC0603X026N | CMP-RES-00602-1 | 1 |
| Yageo_RC0201JR-070RL | RES, 0.0 OHM, 0.5A, 1/20W, 0201 | R33 | RESC0603X026N | CMP-RES-00843-1 | 1 |
| Yageo_RC0402FR-07100RL | RES SMD 100 OHM 1% 1/16W 0402 | R5 | RESC1005X040N | RES-CMP-00538-3 | 1 |
